# T6G (Grand Teton) — schematic parts with pin connectivity, parts 2884–3029 of 8303; source: Cadence DE-HDL packaged netlist (pstxprt.dat, pstxnet.dat, pstchip.dat)

PC148_6  Q_CAP  22UF 4V 20% X6S  pkg C0805  page 220 : 1 = PVDDCR_CPU1_P1 ; 2 = GND
PC149  Q_CAP  560PF 50V 10% EMPTY  pkg C0402  page 215 : 1 = SW_PVDDCR_SOC_P1_SW2 ; 2 = SW_PVDDCR_SOC_P1_SW2_RC
PC149_2  Q_CAP  0.1UF 25V 10% X7R  pkg 0402  page 205 : 1 = SW_P12V_AUX_PVDDIO_P0_FLT ; 2 = GND
PC149_6  Q_CAP  22UF 4V 20% X6S  pkg C0805  page 220 : 1 = PVDDCR_CPU1_P1 ; 2 = GND
PC150  Q_CAP  22UF 16V 20% X6S  pkg C0805  page 226 : 1 = SW_P12V_AUX_PVDD18_S5_P1_FLT ; 2 = GND
PC150_1  Q_CAP  1UF 25V 10% X6S  pkg C0402  page 205 : 1 = SW_P12V_AUX_PVDDIO_P0_FLT ; 2 = GND
PC150_6  Q_CAP  0.1UF 25V 10% X7R  pkg 0402  page 196 : 1 = PVDDCR_CPU0_P0_VCCS ; 2 = GND
PC151  Q_CAP  2.2UF 10V 10% X6S  pkg C0402  page 196 : 1 = PVDDCR_CPU0_P0_VCC6 ; 2 = GND
PC151_2  Q_CAP  1UF 25V 10% X6S  pkg C0402  page 205 : 1 = SW_P12V_AUX_PVDDIO_P0_FLT ; 2 = GND
PC152  Q_CAP  22UF 16V 20% X6S  pkg C0805  page 226 : 1 = SW_P12V_AUX_PVDD18_S5_P1_FLT ; 2 = GND
PC152_1  Q_CAP  22UF 16V 20% X6S  pkg C0805  page 205 : 1 = SW_P12V_AUX_PVDDIO_P0_FLT ; 2 = GND
PC152_C0P0_6  Q_CAP  2.2UF 10V 10% X6S  pkg C0402  page 196 : 1 = PVDDCR_CPU0_P0_PVCC ; 2 = GND
PC153  Q_CAP  0.022UF 25V 10% X7R  pkg 0402  page 226 : 1 = PVDD18_S5_P1_REF ; 2 = GND
PC153_2  Q_CAP  22UF 16V 20% X6S  pkg C0805  page 205 : 1 = SW_P12V_AUX_PVDDIO_P0_FLT ; 2 = GND
PC153_6  Q_CAP  0.1UF 25V 10% X7R  pkg 0402  page 196 : 1 = SW_P12V_AUX_PVDDCR_CPU0_P0_FLT ; 2 = GND
PC154  Q_CAP  560PF 50V 10% EMPTY  pkg C0402  page 203 : 1 = SW_PVDDCR_CPU1_P0_SW6 ; 2 = SW_PVDDCR_CPU1_P0_SW6_RC
PC154_1  Q_CAP  22UF 16V 20% X6S  pkg C0805  page 205 : 1 = SW_P12V_AUX_PVDDIO_P0_FLT ; 2 = GND
PC154_6  Q_CAP  1UF 25V 10% X6S  pkg C0402  page 196 : 1 = SW_P12V_AUX_PVDDCR_CPU0_P0_FLT ; 2 = GND
PC155  Q_CAP  0.22UF 16V 10% X7R  pkg 0402  page 205 : 1 = SW_PVDDIO_P0_BOOT1_R ; 2 = SW_PVDDIO_P0_BOOTR1
PC156  Q_CAP  0.22UF 16V 10% X7R  pkg 0402  page 205 : 1 = SW_PVDDIO_P0_BOOT2_R ; 2 = SW_PVDDIO_P0_BOOTR2
PC157  Q_CAP  560PF 50V 10% EMPTY  pkg C0402  page 203 : 1 = SW_PVDDCR_CPU1_P0_SW5 ; 2 = SW_PVDDCR_CPU1_P0_SW5_RC
PC157_2  Q_CAP  22UF 16V 20% X6S  pkg C0805  page 205 : 1 = SW_P12V_AUX_PVDDIO_P0_FLT ; 2 = GND
PC157_6  Q_CAP  22UF 16V 20% X6S  pkg C0805  page 196 : 1 = SW_P12V_AUX_PVDDCR_CPU0_P0_FLT ; 2 = GND
PC158  Q_CAP  560PF 50V 10% EMPTY  pkg C0402  page 205 : 1 = SW_PVDDIO_P0_SW1 ; 2 = SW_PVDDIO_P0_SW1_RC
PC158_1  Q_CAP  22UF 16V 20% X6S  pkg C0805  page 205 : 1 = SW_P12V_AUX_PVDDIO_P0_FLT ; 2 = GND
PC158_6  Q_CAP  22UF 16V 20% X6S  pkg C0805  page 196 : 1 = SW_P12V_AUX_PVDDCR_CPU0_P0_FLT ; 2 = GND
PC159  Q_CAP  560PF 50V 10% EMPTY  pkg C0402  page 205 : 1 = SW_PVDDIO_P0_SW2 ; 2 = SW_PVDDIO_P0_SW2_RC
PC159_2  Q_CAP  22UF 16V 20% X6S  pkg C0805  page 205 : 1 = SW_P12V_AUX_PVDDIO_P0_FLT ; 2 = GND
PC159_6  Q_CAP  22UF 16V 20% X6S  pkg C0805  page 196 : 1 = SW_P12V_AUX_PVDDCR_CPU0_P0_FLT ; 2 = GND
PC160  Q_CAPP  470UF 2.5V 20% EMPTY  pkg SMLF  page 205 : 1 = PVDDIO_P0 ; 2 = GND
PC161  Q_CAP  0.22UF 16V 10% X7R  pkg 0402  page 196 : 1 = SW_PVDDCR_CPU0_P0_BOOT6_RC ; 2 = SW_PVDDCR_CPU0_P0_PH6
PC162  Q_CAPP  470UF 2.5V 20% SPCAP  pkg SMLF  page 205 : 1 = PVDDIO_P0 ; 2 = GND
PC163  Q_CAP  560PF 50V 10% EMPTY  pkg C0402  page 206 : 1 = SW_PVDDIO_P0_SW4 ; 2 = SW_PVDDIO_P0_SW4_RC
PC163_6  Q_CAP  22UF 4V 20% X6S  pkg C0805  page 196 : 1 = PVDDCR_CPU0_P0 ; 2 = GND
PC164  Q_CAPP  270UF 16V 20% OSCON  pkg THLF  page 205 : 1 = SW_P12V_AUX_PVDDIO_P0_FLT ; 2 = GND
PC165  Q_CAPP  470UF 2.5V 20% SPCAP  pkg SMLF  page 205 : 1 = PVDDIO_P0 ; 2 = GND
PC166  Q_CAP  560PF 50V 10% EMPTY  pkg C0402  page 206 : 1 = SW_PVDDIO_P0_SW3 ; 2 = SW_PVDDIO_P0_SW3_RC
PC166_1  Q_CAP  22UF 4V 20% X6S  pkg C0805  page 205 : 1 = PVDDIO_P0 ; 2 = GND
PC166_6  Q_CAP  22UF 4V 20% X6S  pkg C0805  page 196 : 1 = PVDDCR_CPU0_P0 ; 2 = GND
PC168  Q_CAP  560PF 50V 10% EMPTY  pkg C0402  page 208 : 1 = SW_PVDD11_S3_P0_SW2 ; 2 = SW_PVDD11_S3_P0_SW2_RC
PC168_2  Q_CAP  22UF 4V 20% X6S  pkg C0805  page 205 : 1 = PVDDIO_P0 ; 2 = GND
PC169  Q_CAP  560PF 50V 10% EMPTY  pkg C0402  page 208 : 1 = SW_PVDD11_S3_P0_SW1 ; 2 = SW_PVDD11_S3_P0_SW1_RC
PC169_1  Q_CAP  22UF 4V 20% X6S  pkg C0805  page 205 : 1 = PVDDIO_P0 ; 2 = GND
PC170  Q_CAP  560PF 50V 10% EMPTY  pkg C0402  page 211 : 1 = SW_PVDDCR_CPU0_P1_SW1 ; 2 = SW_PVDDCR_CPU0_P1_SW1_RC
PC170_2  Q_CAP  22UF 4V 20% X6S  pkg C0805  page 205 : 1 = PVDDIO_P0 ; 2 = GND
PC171  Q_CAP  2.2UF 10V 10% X6S  pkg C0402  page 206 : 1 = PVDDIO_P0_VCC4 ; 2 = GND
PC172  Q_CAP  2.2UF 10V 10% X6S  pkg C0402  page 206 : 1 = PVDDIO_P0_VCC3 ; 2 = GND
PC173  Q_CAP  560PF 50V 10% EMPTY  pkg C0402  page 211 : 1 = SW_PVDDCR_CPU0_P1_SW2 ; 2 = SW_PVDDCR_CPU0_P1_SW2_RC
PC173_IOP0_4  Q_CAP  2.2UF 10V 10% X6S  pkg C0402  page 206 : 1 = PVDDCR_CPU1_P0_PVCC ; 2 = GND
PC174  Q_CAP  560PF 50V 10% EMPTY  pkg C0402  page 222 : 1 = SW_PVDDIO_P1_SW1 ; 2 = SW_PVDDIO_P1_SW1_RC
PC174_IOP0_3  Q_CAP  2.2UF 10V 10% X6S  pkg C0402  page 206 : 1 = PVDDCR_CPU1_P0_PVCC ; 2 = GND
PC175  Q_CAP  560PF 50V 10% EMPTY  pkg C0402  page 222 : 1 = SW_PVDDIO_P1_SW2 ; 2 = SW_PVDDIO_P1_SW2_RC
PC175_9  Q_CAP  0.1UF 25V 10% X7R  pkg 0402  page 206 : 1 = PVDDCR_CPU1_P0_VCCS ; 2 = GND
PC176  Q_CAP  560PF 50V 10% EMPTY  pkg C0402  page 223 : 1 = SW_PVDDIO_P1_SW4 ; 2 = SW_PVDDIO_P1_SW4_RC
PC176_10  Q_CAP  0.1UF 25V 10% X7R  pkg 0402  page 206 : 1 = PVDDCR_CPU1_P0_VCCS ; 2 = GND
PC177  Q_CAP  560PF 50V 10% EMPTY  pkg C0402  page 223 : 1 = SW_PVDDIO_P1_SW3 ; 2 = SW_PVDDIO_P1_SW3_RC
PC177_3  Q_CAP  0.1UF 25V 10% X7R  pkg 0402  page 206 : 1 = SW_P12V_AUX_PVDDIO_P0_FLT ; 2 = GND
PC178  Q_CAP  560PF 50V 10% EMPTY  pkg C0402  page 194 : 1 = SW_PVDDCR_CPU0_P0_SW1 ; 2 = SW_PVDDCR_CPU0_P0_SW1_RC
PC178_4  Q_CAP  0.1UF 25V 10% X7R  pkg 0402  page 206 : 1 = SW_P12V_AUX_PVDDIO_P0_FLT ; 2 = GND
PC179  Q_CAP  560PF 50V 10% EMPTY  pkg C0402  page 194 : 1 = SW_PVDDCR_CPU0_P0_SW2 ; 2 = SW_PVDDCR_CPU0_P0_SW2_RC
PC179_3  Q_CAP  1UF 25V 10% X6S  pkg C0402  page 206 : 1 = SW_P12V_AUX_PVDDIO_P0_FLT ; 2 = GND
PC180  Q_CAP  560PF 50V 10% EMPTY  pkg C0402  page 195 : 1 = SW_PVDDCR_CPU0_P0_SW3 ; 2 = SW_PVDDCR_CPU0_P0_SW3_RC
PC180_4  Q_CAP  1UF 25V 10% X6S  pkg C0402  page 206 : 1 = SW_P12V_AUX_PVDDIO_P0_FLT ; 2 = GND
PC181  Q_CAP  560PF 50V 10% EMPTY  pkg C0402  page 195 : 1 = SW_PVDDCR_CPU0_P0_SW4 ; 2 = SW_PVDDCR_CPU0_P0_SW4_RC
PC181_3  Q_CAP  22UF 16V 20% X6S  pkg C0805  page 206 : 1 = SW_P12V_AUX_PVDDIO_P0_FLT ; 2 = GND
PC182  Q_CAP  560PF 50V 10% EMPTY  pkg C0402  page 196 : 1 = SW_PVDDCR_CPU0_P0_SW6 ; 2 = SW_PVDDCR_CPU0_P0_SW6_RC
PC182_4  Q_CAP  22UF 16V 20% X6S  pkg C0805  page 206 : 1 = SW_P12V_AUX_PVDDIO_P0_FLT ; 2 = GND
PC183  Q_CAP  0.22UF 16V 10% X7R  pkg 0402  page 206 : 1 = SW_PVDDIO_P0_BOOT4_R ; 2 = SW_PVDDIO_P0_BOOTR4
PC184  Q_CAP  560PF 50V 10% EMPTY  pkg C0402  page 196 : 1 = SW_PVDDCR_CPU0_P0_SW5 ; 2 = SW_PVDDCR_CPU0_P0_SW5_RC
PC184_3  Q_CAP  22UF 16V 20% X6S  pkg C0805  page 206 : 1 = SW_P12V_AUX_PVDDIO_P0_FLT ; 2 = GND
PC185  Q_CAP  560PF 50V 10% EMPTY  pkg C0402  page 198 : 1 = SW_PVDDCR_SOC_P0_SW1 ; 2 = SW_PVDDCR_SOC_P0_SW1_RC
PC185_4  Q_CAP  22UF 16V 20% X6S  pkg C0805  page 206 : 1 = SW_P12V_AUX_PVDDIO_P0_FLT ; 2 = GND
PC186  Q_CAP  0.22UF 16V 10% X7R  pkg 0402  page 206 : 1 = SW_PVDDIO_P0_BOOT3_R ; 2 = SW_PVDDIO_P0_BOOTR3
PC187  Q_CAP  560PF 50V 10% EMPTY  pkg C0402  page 198 : 1 = SW_PVDDCR_SOC_P0_SW2 ; 2 = SW_PVDDCR_SOC_P0_SW2_RC
PC187_3  Q_CAP  22UF 16V 20% X6S  pkg C0805  page 206 : 1 = SW_P12V_AUX_PVDDIO_P0_FLT ; 2 = GND
PC188  Q_CAP  560PF 50V 10% EMPTY  pkg C0402  page 199 : 1 = SW_PVDDCR_SOC_P0_SW3 ; 2 = SW_PVDDCR_SOC_P0_SW3_RC
PC188_4  Q_CAP  22UF 16V 20% X6S  pkg C0805  page 206 : 1 = SW_P12V_AUX_PVDDIO_P0_FLT ; 2 = GND
PC189  Q_CAP  560PF 50V 10% EMPTY  pkg C0402  page 201 : 1 = SW_PVDDCR_CPU1_P0_SW1 ; 2 = SW_PVDDCR_CPU1_P0_SW1_RC
PC189_4  Q_CAP  22UF 4V 20% X6S  pkg C0805  page 206 : 1 = PVDDIO_P0 ; 2 = GND
PC190  Q_CAP  560PF 50V 10% EMPTY  pkg C0402  page 201 : 1 = SW_PVDDCR_CPU1_P0_SW2 ; 2 = SW_PVDDCR_CPU1_P0_SW2_RC
PC190_3  Q_CAP  22UF 4V 20% X6S  pkg C0805  page 206 : 1 = PVDDIO_P0 ; 2 = GND
PC191  Q_CAP  560PF 50V 10% EMPTY  pkg C0402  page 202 : 1 = SW_PVDDCR_CPU1_P0_SW4 ; 2 = SW_PVDDCR_CPU1_P0_SW4_RC
PC191_4  Q_CAP  22UF 4V 20% X6S  pkg C0805  page 206 : 1 = PVDDIO_P0 ; 2 = GND
PC192  Q_CAP  560PF 50V 10% EMPTY  pkg C0402  page 202 : 1 = SW_PVDDCR_CPU1_P0_SW3 ; 2 = SW_PVDDCR_CPU1_P0_SW3_RC
PC192_3  Q_CAP  22UF 4V 20% X6S  pkg C0805  page 206 : 1 = PVDDIO_P0 ; 2 = GND
PC193  Q_CAP  0.1UF 25V 10% X7R  pkg 0402  page 207 : 1 = PVDD11_S3_P0_VMON ; 2 = GND
PC194  Q_CAP  3300PF 50V 10% X7R  pkg 0402  page 207 : 1 = VSENSE_PVDD11_S3_P0_R ; 2 = VSENSE_VSS_SENSE_C_P0
PC195  Q_CAP  560PF 50V 10% EMPTY  pkg C0402  page 216 : 1 = SW_PVDDCR_SOC_P1_SW3 ; 2 = SW_PVDDCR_SOC_P1_SW3_RC
PC198  Q_CAP  470PF 50V 10% X7R  pkg 0402  page 207 : 1 = PVDD11_S3_P0_TEMP0 ; 2 = GND
PC199  Q_CAP  10UF 6.3V 20% X6S  pkg C0402  page 207 : 1 = PVDD11_S3_P0_VCCS ; 2 = GND
PC200  Q_CAP  1UF 16V 10% X6S  pkg C0402  page 207 : 1 = PVDD11_S3_P0_VCC ; 2 = GND
PC201  Q_CAP  560PF 50V 10% EMPTY  pkg C0402  page 218 : 1 = SW_PVDDCR_CPU1_P1_SW1 ; 2 = SW_PVDDCR_CPU1_P1_SW1_RC
PC201_1  Q_CAP  0.1UF 25V 10% X7R  pkg 0402  page 208 : 1 = PVDD11_S3_P0_VCCS ; 2 = GND
PC202  Q_CAP  560PF 50V 10% EMPTY  pkg C0402  page 218 : 1 = SW_PVDDCR_CPU1_P1_SW2 ; 2 = SW_PVDDCR_CPU1_P1_SW2_RC
PC202_2  Q_CAP  0.1UF 25V 10% X7R  pkg 0402  page 208 : 1 = PVDD11_S3_P0_VCCS ; 2 = GND
PC203  Q_CAP  2.2UF 10V 10% X6S  pkg C0402  page 208 : 1 = PVDD11_S3_P0_VCC1 ; 2 = GND
PC204  Q_CAP  2.2UF 10V 10% X6S  pkg C0402  page 208 : 1 = PVDD11_S3_P0_VCC2 ; 2 = GND
PC205  Q_CAP  560PF 50V 10% EMPTY  pkg C0402  page 219 : 1 = SW_PVDDCR_CPU1_P1_SW4 ; 2 = SW_PVDDCR_CPU1_P1_SW4_RC
PC205_11P0_1  Q_CAP  2.2UF 10V 10% X6S  pkg C0402  page 208 : 1 = PVDD11_S3_P0_PVCC ; 2 = GND
PC206  Q_CAP  560PF 50V 10% EMPTY  pkg C0402  page 219 : 1 = SW_PVDDCR_CPU1_P1_SW3 ; 2 = SW_PVDDCR_CPU1_P1_SW3_RC
PC206_11P0_2  Q_CAP  2.2UF 10V 10% X6S  pkg C0402  page 208 : 1 = PVDD11_S3_P0_PVCC ; 2 = GND
PC207  Q_CAP  560PF 50V 10% EMPTY  pkg C0402  page 220 : 1 = SW_PVDDCR_CPU1_P1_SW5 ; 2 = SW_PVDDCR_CPU1_P1_SW5_RC
PC207_1  Q_CAP  0.1UF 25V 10% X7R  pkg 0402  page 208 : 1 = SW_P12V_AUX_PVDD11_S3_P0_FLT ; 2 = GND
PC208  Q_CAP  560PF 50V 10% EMPTY  pkg C0402  page 220 : 1 = SW_PVDDCR_CPU1_P1_SW6 ; 2 = SW_PVDDCR_CPU1_P1_SW6_RC
PC208_2  Q_CAP  0.1UF 25V 10% X7R  pkg 0402  page 208 : 1 = SW_P12V_AUX_PVDD11_S3_P0_FLT ; 2 = GND
PC209  Q_CAP  0.22UF 16V 10% X7R  pkg 0402  page 209 : 1 = SW_PVDD18_S5_P0_BST_R ; 2 = SW_PVDD18_S5_P0_SW
PC209_1  Q_CAP  1UF 25V 10% X6S  pkg C0402  page 208 : 1 = SW_P12V_AUX_PVDD11_S3_P0_FLT ; 2 = GND
PC210_2  Q_CAP  1UF 25V 10% X6S  pkg C0402  page 208 : 1 = SW_P12V_AUX_PVDD11_S3_P0_FLT ; 2 = GND
PC211_1  Q_CAP  22UF 16V 20% X6S  pkg C0805  page 208 : 1 = SW_P12V_AUX_PVDD11_S3_P0_FLT ; 2 = GND
PC212  Q_CAP  1UF 25V 10% X6S  pkg C0402  page 209 : 1 = PVDD18_S5_P0_VCC ; 2 = GND
PC212_2  Q_CAP  22UF 16V 20% X6S  pkg C0805  page 208 : 1 = SW_P12V_AUX_PVDD11_S3_P0_FLT ; 2 = GND
PC213_1  Q_CAP  22UF 16V 20% X6S  pkg C0805  page 208 : 1 = SW_P12V_AUX_PVDD11_S3_P0_FLT ; 2 = GND
PC214_2  Q_CAP  22UF 16V 20% X6S  pkg C0805  page 208 : 1 = SW_P12V_AUX_PVDD11_S3_P0_FLT ; 2 = GND
PC215  Q_CAP  0.1UF 25V 10% X7R  pkg 0402  page 209 : 1 = PVDD18_S5_P0 ; 2 = GND
PC215_1  Q_CAP  22UF 16V 20% X6S  pkg C0805  page 208 : 1 = SW_P12V_AUX_PVDD11_S3_P0_FLT ; 2 = GND
PC216_2  Q_CAP  22UF 16V 20% X6S  pkg C0805  page 208 : 1 = SW_P12V_AUX_PVDD11_S3_P0_FLT ; 2 = GND
PC217  Q_CAP  0.22UF 16V 10% X7R  pkg 0402  page 208 : 1 = SW_PVDD11_S3_P0_BOOT1_RC ; 2 = SW_PVDD11_S3_P0_PH1
PC218  Q_CAP  0.22UF 16V 10% X7R  pkg 0402  page 208 : 1 = SW_PVDD11_S3_P0_BOOT2_RC ; 2 = SW_PVDD11_S3_P0_PH2
PC218_2  Q_CAP  22UF 16V 20% X6S  pkg C0805  page 208 : 1 = SW_P12V_AUX_PVDD11_S3_P0_FLT ; 2 = GND
PC219_1  Q_CAP  22UF 16V 20% X6S  pkg C0805  page 208 : 1 = SW_P12V_AUX_PVDD11_S3_P0_FLT ; 2 = GND
PC220  Q_CAPP  270UF 16V 20% OSCON  pkg THLF  page 208 : 1 = SW_P12V_AUX_PVDD11_S3_P0_FLT ; 2 = GND
PC221_2  Q_CAP  22UF 4V 20% X6S  pkg C0805  page 208 : 1 = PVDD11_S3_P0 ; 2 = GND
PC222  Q_CAP  0.1UF 25V 10% X7R  pkg 0402  page 208 : 1 = PVDD11_S3_P0 ; 2 = GND
PC223  Q_CAPP  470UF 2.5V 20% SPCAP  pkg SMLF  page 208 : 1 = PVDD11_S3_P0 ; 2 = GND
PC224_1  Q_CAP  22UF 4V 20% X6S  pkg C0805  page 208 : 1 = PVDD11_S3_P0 ; 2 = GND
PC225_2  Q_CAP  22UF 4V 20% X6S  pkg C0805  page 208 : 1 = PVDD11_S3_P0 ; 2 = GND
PC226  Q_CAPP  470UF 2.5V 20% SPCAP  pkg SMLF  page 208 : 1 = PVDD11_S3_P0 ; 2 = GND
PC227  Q_CAP  22UF 16V 20% X6S  pkg C0805  page 209 : 1 = SW_P12V_AUX_PVDD18_S5_P0_FLT ; 2 = GND
PC227_1  Q_CAP  22UF 4V 20% X6S  pkg C0805  page 208 : 1 = PVDD11_S3_P0 ; 2 = GND
PC228  Q_CAPP  390UF 2.5V 20% ALUM  pkg SMLF  page 208 : 1 = PVDD11_S3_P0 ; 2 = GND
PC229  Q_CAPP  390UF 2.5V 20% ALUM  pkg SMLF  page 208 : 1 = PVDD11_S3_P0 ; 2 = GND
PC230  Q_CAPP  390UF 2.5V 20% ALUM  pkg SMLF  page 208 : 1 = PVDD11_S3_P0 ; 2 = GND
PC237  Q_CAP  1UF 25V 10% X6S  pkg C0402  page 209 : 1 = SW_P12V_AUX_PVDD18_S5_P0_FLT ; 2 = GND
PC243  Q_CAP  0.1UF 25V 10% X7R  pkg 0402  page 210 : 1 = PVDDCR_CPU0_P1_VMON ; 2 = GND
PC244  Q_CAP  3300PF 50V 10% X7R  pkg 0402  page 210 : 1 = VSENSE_PVDDCR_CPU0_P1_VSEN0 ; 2 = VSENSE_VSS_SENSE_A_P1
PC245  Q_CAP  3300PF 50V 10% X7R  pkg 0402  page 210 : 1 = VSENSE_PVDDCR_SOC_P1_VSEN1 ; 2 = VSENSE_VSS_SENSE_A_P1
PC247  Q_CAP  1UF 6.3V 10% X7R  pkg 0402  page 210 : 1 = PVDD18_S5_P1 ; 2 = GND
PC250  Q_CAP  470PF 50V 10% X7R  pkg 0402  page 210 : 1 = PVDDCR_CPU0_P1_TEMP0 ; 2 = GND
PC251  Q_CAP  10UF 6.3V 20% X6S  pkg C0402  page 210 : 1 = PVDDCR_CPU0_P1_VCCS ; 2 = GND
PC252  Q_CAP  1UF 16V 10% X6S  pkg C0402  page 210 : 1 = PVDDCR_CPU0_P1_VCC ; 2 = GND
PC253  Q_CAP  470PF 50V 10% X7R  pkg 0402  page 210 : 1 = PVDDCR_SOC_P1_TEMP1 ; 2 = GND
PC254  Q_CAP  22UF 16V 20% X6S  pkg C0805  page 209 : 1 = SW_P12V_AUX_PVDD18_S5_P0_FLT ; 2 = GND
PC254_1  Q_CAP  0.1UF 25V 10% X7R  pkg 0402  page 211 : 1 = PVDDCR_CPU0_P1_VCCS ; 2 = GND
PC255  Q_CAP  560PF 50V 10% EMPTY  pkg C0402  page 225 : 1 = SW_PVDD11_S3_P1_SW2 ; 2 = SW_PVDD11_S3_P1_SW2_RC
PC255_2  Q_CAP  0.1UF 25V 10% X7R  pkg 0402  page 211 : 1 = PVDDCR_CPU0_P1_VCCS ; 2 = GND
PC256  Q_CAP  2.2UF 10V 10% X6S  pkg C0402  page 211 : 1 = PVDDCR_CPU0_P1_VCC1 ; 2 = GND
